(kicad_pcb
	(version 20260206)
	(generator "pcbnew")
	(generator_version "10.0")
	(general
		(thickness 1.6)
		(legacy_teardrops no)
	)
	(paper "A4")
	(title_block
		(title "01162023_DA0F0TEBIF0_F0T_Expander_BD_F_brd_V02_OCP.brd")
		(comment 1 "Grand Teton / footprints 3113-3118 of 9728")
	)
	(layers
		(0 "F.Cu" signal "TOP")
		(4 "In1.Cu" signal "GND")
		(6 "In2.Cu" signal "VCC")
		(8 "In3.Cu" signal "VCC1")
		(10 "In4.Cu" signal "GND1")
		(12 "In5.Cu" signal "IN1")
		(14 "In6.Cu" signal "GND2")
		(16 "In7.Cu" signal "IN2")
		(18 "In8.Cu" signal "GND3")
		(20 "In9.Cu" signal "IN3")
		(22 "In10.Cu" signal "GND4")
		(24 "In11.Cu" signal "IN4")
		(26 "In12.Cu" signal "GND5")
		(28 "In13.Cu" signal "IN5")
		(30 "In14.Cu" signal "GND6")
		(32 "In15.Cu" signal "IN6")
		(34 "In16.Cu" signal "GND7")
		(2 "B.Cu" signal "BOTTOM")
		(9 "F.Adhes" user "F.Adhesive")
		(11 "B.Adhes" user "B.Adhesive")
		(13 "F.Paste" user "Package Geometry/Pastemask Top")
		(15 "B.Paste" user "Package Geometry/Pastemask Bottom")
		(5 "F.SilkS" user "Ref Des/Silkscreen Top")
		(7 "B.SilkS" user "Ref Des/Silkscreen Bottom")
		(1 "F.Mask" user "Board Geometry/Soldermask Top")
		(3 "B.Mask" user "Board Geometry/Soldermask Bottom")
		(17 "Dwgs.User" user "User.Drawings")
		(19 "Cmts.User" user "User.Comments")
		(21 "Eco1.User" user "User.Eco1")
		(23 "Eco2.User" user "User.Eco2")
		(25 "Edge.Cuts" user "Board Geometry/Outline")
		(27 "Margin" user)
		(31 "F.CrtYd" user "Package Geometry/Place Bound Top")
		(29 "B.CrtYd" user "Package Geometry/Place Bound Bottom")
		(35 "F.Fab" user "Ref Des/Assembly Top")
		(33 "B.Fab" user "Ref Des/Assembly Bottom")
	)
	(footprint ""
		(layer "F.Cu")
		(at 359.156 -182.118)
		(property "Reference" "R4681"
			(at 0 0 0)
			(layer "F.SilkS")
			(hide yes)
			(effects
				(font
					(size 1.27 1.27)
				)
			)
		)
		(property "Value" ""
			(at 0 0 0)
			(layer "F.Fab")
			(effects
				(font
					(size 1.27 1.27)
				)
			)
		)
		(duplicate_pad_numbers_are_jumpers no)
		(fp_line
			(start -0.7874 -0.4064)
			(end 0.7874 -0.4064)
			(stroke
				(width 0.1524)
				(type default)
			)
			(layer "F.SilkS")
		)
		(fp_line
			(start -0.7874 0.4064)
			(end -0.7874 -0.4064)
			(stroke
				(width 0.1524)
				(type default)
			)
			(layer "F.SilkS")
		)
		(fp_line
			(start 0.7874 -0.4064)
			(end 0.7874 0.4064)
			(stroke
				(width 0.1524)
				(type default)
			)
			(layer "F.SilkS")
		)
		(fp_line
			(start 0.7874 0.4064)
			(end -0.7874 0.4064)
			(stroke
				(width 0.1524)
				(type default)
			)
			(layer "F.SilkS")
		)
		(fp_line
			(start -0.67945 -0.305054)
			(end -0.12065 -0.305054)
			(stroke
				(width 0.1)
				(type default)
			)
			(layer "F.Fab")
		)
		(fp_line
			(start -0.67945 0.3048)
			(end -0.67945 -0.305054)
			(stroke
				(width 0.1)
				(type default)
			)
			(layer "F.Fab")
		)
		(fp_line
			(start -0.12065 -0.305054)
			(end -0.12065 -0.2794)
			(stroke
				(width 0.1)
				(type default)
			)
			(layer "F.Fab")
		)
		(fp_line
			(start -0.12065 -0.2794)
			(end 0.12065 -0.2794)
			(stroke
				(width 0.1)
				(type default)
			)
			(layer "F.Fab")
		)
		(fp_line
			(start -0.12065 0.2794)
			(end -0.12065 0.3048)
			(stroke
				(width 0.1)
				(type default)
			)
			(layer "F.Fab")
		)
		(fp_line
			(start -0.12065 0.3048)
			(end -0.67945 0.3048)
			(stroke
				(width 0.1)
				(type default)
			)
			(layer "F.Fab")
		)
		(fp_line
			(start 0.120396 0.2794)
			(end -0.12065 0.2794)
			(stroke
				(width 0.1)
				(type default)
			)
			(layer "F.Fab")
		)
		(fp_line
			(start 0.120396 0.3048)
			(end 0.120396 0.2794)
			(stroke
				(width 0.1)
				(type default)
			)
			(layer "F.Fab")
		)
		(fp_line
			(start 0.12065 -0.3048)
			(end 0.67945 -0.3048)
			(stroke
				(width 0.1)
				(type default)
			)
			(layer "F.Fab")
		)
		(fp_line
			(start 0.12065 -0.2794)
			(end 0.12065 -0.3048)
			(stroke
				(width 0.1)
				(type default)
			)
			(layer "F.Fab")
		)
		(fp_line
			(start 0.67945 -0.3048)
			(end 0.67945 0.3048)
			(stroke
				(width 0.1)
				(type default)
			)
			(layer "F.Fab")
		)
		(fp_line
			(start 0.67945 0.3048)
			(end 0.120396 0.3048)
			(stroke
				(width 0.1)
				(type default)
			)
			(layer "F.Fab")
		)
		(pad "1" smd circle
			(at -0.40005 0)
			(size 0 0)
			(layers "F.Cu" "F.Mask" "F.Paste")
			(net "PEX1_PCA9555_INT_N")
		)
		(pad "2" smd circle
			(at 0.40005 0)
			(size 0 0)
			(layers "F.Cu" "F.Mask" "F.Paste")
			(net "PEX1_PCA9555_1_INT_N")
		)
	)
	(footprint ""
		(layer "F.Cu")
		(at 336.467704 -51.019456)
		(property "Reference" "PC446"
			(at 0 0 0)
			(layer "F.SilkS")
			(hide yes)
			(effects
				(font
					(size 1.27 1.27)
				)
			)
		)
		(property "Value" ""
			(at 0 0 0)
			(layer "F.Fab")
			(effects
				(font
					(size 1.27 1.27)
				)
			)
		)
		(duplicate_pad_numbers_are_jumpers no)
		(fp_line
			(start -0.7874 -0.4064)
			(end 0.7874 -0.4064)
			(stroke
				(width 0.1524)
				(type default)
			)
			(layer "F.SilkS")
		)
		(fp_line
			(start -0.7874 0.4064)
			(end -0.7874 -0.4064)
			(stroke
				(width 0.1524)
				(type default)
			)
			(layer "F.SilkS")
		)
		(fp_line
			(start 0.7874 -0.4064)
			(end 0.7874 0.4064)
			(stroke
				(width 0.1524)
				(type default)
			)
			(layer "F.SilkS")
		)
		(fp_line
			(start 0.7874 0.4064)
			(end -0.7874 0.4064)
			(stroke
				(width 0.1524)
				(type default)
			)
			(layer "F.SilkS")
		)
		(fp_line
			(start -0.67945 -0.305054)
			(end -0.12065 -0.305054)
			(stroke
				(width 0.1)
				(type default)
			)
			(layer "F.Fab")
		)
		(fp_line
			(start -0.67945 0.3048)
			(end -0.67945 -0.305054)
			(stroke
				(width 0.1)
				(type default)
			)
			(layer "F.Fab")
		)
		(fp_line
			(start -0.12065 -0.305054)
			(end -0.12065 -0.2794)
			(stroke
				(width 0.1)
				(type default)
			)
			(layer "F.Fab")
		)
		(fp_line
			(start -0.12065 -0.2794)
			(end 0.12065 -0.2794)
			(stroke
				(width 0.1)
				(type default)
			)
			(layer "F.Fab")
		)
		(fp_line
			(start -0.12065 0.2794)
			(end -0.12065 0.3048)
			(stroke
				(width 0.1)
				(type default)
			)
			(layer "F.Fab")
		)
		(fp_line
			(start -0.12065 0.3048)
			(end -0.67945 0.3048)
			(stroke
				(width 0.1)
				(type default)
			)
			(layer "F.Fab")
		)
		(fp_line
			(start 0.120396 0.2794)
			(end -0.12065 0.2794)
			(stroke
				(width 0.1)
				(type default)
			)
			(layer "F.Fab")
		)
		(fp_line
			(start 0.120396 0.3048)
			(end 0.120396 0.2794)
			(stroke
				(width 0.1)
				(type default)
			)
			(layer "F.Fab")
		)
		(fp_line
			(start 0.12065 -0.3048)
			(end 0.67945 -0.3048)
			(stroke
				(width 0.1)
				(type default)
			)
			(layer "F.Fab")
		)
		(fp_line
			(start 0.12065 -0.2794)
			(end 0.12065 -0.3048)
			(stroke
				(width 0.1)
				(type default)
			)
			(layer "F.Fab")
		)
		(fp_line
			(start 0.67945 -0.3048)
			(end 0.67945 0.3048)
			(stroke
				(width 0.1)
				(type default)
			)
			(layer "F.Fab")
		)
		(fp_line
			(start 0.67945 0.3048)
			(end 0.120396 0.3048)
			(stroke
				(width 0.1)
				(type default)
			)
			(layer "F.Fab")
		)
		(pad "1" smd circle
			(at -0.40005 0)
			(size 0 0)
			(layers "F.Cu" "F.Mask" "F.Paste")
			(net "P12V_SSD11_SS")
		)
		(pad "2" smd circle
			(at 0.40005 0)
			(size 0 0)
			(layers "F.Cu" "F.Mask" "F.Paste")
			(net "GND")
		)
	)
	(footprint ""
		(layer "F.Cu")
		(at 443.571376 -121.291858)
		(property "Reference" "PU53"
			(at -0.973836 2.865628 0)
			(unlocked yes)
			(layer "F.SilkS")
			(effects
				(font
					(size 0.7874 0.5842)
					(thickness 0.1524)
				)
				(justify left)
			)
		)
		(property "Value" ""
			(at 0 0 0)
			(layer "F.Fab")
			(effects
				(font
					(size 1.27 1.27)
				)
			)
		)
		(duplicate_pad_numbers_are_jumpers no)
		(fp_line
			(start -1.943608 -1.549908)
			(end 1.943608 -1.549908)
			(stroke
				(width 0.1524)
				(type default)
			)
			(layer "F.SilkS")
		)
		(fp_line
			(start -1.943608 1.549908)
			(end -1.943608 -1.549908)
			(stroke
				(width 0.1524)
				(type default)
			)
			(layer "F.SilkS")
		)
		(fp_line
			(start 1.943608 -1.549908)
			(end 1.943608 1.549908)
			(stroke
				(width 0.1524)
				(type default)
			)
			(layer "F.SilkS")
		)
		(fp_line
			(start 1.943608 1.549908)
			(end -1.943608 1.549908)
			(stroke
				(width 0.1524)
				(type default)
			)
			(layer "F.SilkS")
		)
		(fp_poly
			(pts
				(xy -2.019808 -1.549908) (xy -1.257808 -1.549908) (xy -1.257808 -1.880108) (xy -2.019808 -1.880108)
			)
			(stroke
				(width 0)
				(type default)
			)
			(fill yes)
			(layer "F.SilkS")
		)
		(fp_line
			(start -1.549908 -1.549908)
			(end 1.549908 -1.549908)
			(stroke
				(width 0.1)
				(type default)
			)
			(layer "F.Fab")
		)
		(fp_line
			(start -1.549908 1.549908)
			(end -1.549908 -1.549908)
			(stroke
				(width 0.1)
				(type default)
			)
			(layer "F.Fab")
		)
		(fp_line
			(start 1.549908 -1.549908)
			(end 1.549908 1.549908)
			(stroke
				(width 0.1)
				(type default)
			)
			(layer "F.Fab")
		)
		(fp_line
			(start 1.549908 1.549908)
			(end -1.549908 1.549908)
			(stroke
				(width 0.1)
				(type default)
			)
			(layer "F.Fab")
		)
		(fp_poly
			(pts
				(xy -2.019808 -1.549908) (xy -1.257808 -1.549908) (xy -1.257808 -1.880108) (xy -2.019808 -1.880108)
			)
			(stroke
				(width 0)
				(type default)
			)
			(fill yes)
			(layer "F.Fab")
		)
		(pad "1" smd rect
			(at -1.500124 -1.249934 270)
			(size 0.2794 0.6096)
			(layers "F.Cu" "F.Mask" "F.Paste")
			(net "P3V3_NIC7")
		)
		(pad "2" smd rect
			(at -1.500124 -0.750062 270)
			(size 0.2794 0.6096)
			(layers "F.Cu" "F.Mask" "F.Paste")
			(net "P3V3_NIC7")
		)
		(pad "3" smd rect
			(at -1.500124 -0.249936 270)
			(size 0.2794 0.6096)
			(layers "F.Cu" "F.Mask" "F.Paste")
			(net "P3V3_NIC7")
		)
		(pad "4" smd rect
			(at -1.500124 0.249936 270)
			(size 0.2794 0.6096)
			(layers "F.Cu" "F.Mask" "F.Paste")
			(net "P3V3_NIC7")
		)
		(pad "5" smd rect
			(at -1.500124 0.750062 270)
			(size 0.2794 0.6096)
			(layers "F.Cu" "F.Mask" "F.Paste")
			(net "P3V3_NIC7")
		)
		(pad "6" smd rect
			(at -1.500124 1.249934 270)
			(size 0.2794 0.6096)
			(layers "F.Cu" "F.Mask" "F.Paste")
			(net "GND")
		)
		(pad "7" smd rect
			(at 1.500124 1.249934 270)
			(size 0.2794 0.6096)
			(layers "F.Cu" "F.Mask" "F.Paste")
			(net "P3V3_NIC7_SS")
		)
		(pad "8" smd rect
			(at 1.500124 0.750062 270)
			(size 0.2794 0.6096)
			(layers "F.Cu" "F.Mask" "F.Paste")
			(net "PWRGD_P3V3_NIC7")
		)
		(pad "9" smd rect
			(at 1.500124 0.249936 270)
			(size 0.2794 0.6096)
			(layers "F.Cu" "F.Mask" "F.Paste")
			(net "P3V3_NIC7_OCP")
		)
		(pad "10" smd rect
			(at 1.500124 -0.249936 270)
			(size 0.2794 0.6096)
			(layers "F.Cu" "F.Mask" "F.Paste")
			(net "P5V_AUX")
		)
		(pad "11" smd rect
			(at 1.500124 -0.750062 270)
			(size 0.2794 0.6096)
			(layers "F.Cu" "F.Mask" "F.Paste")
			(net "HP_NIC7_EN")
		)
		(pad "12" smd rect
			(at 1.500124 -1.249934 270)
			(size 0.2794 0.6096)
			(layers "F.Cu" "F.Mask" "F.Paste")
			(net "P3V3_AUX")
		)
		(pad "13" smd rect
			(at 0 0)
			(size 1.9812 2.7178)
			(layers "F.Cu" "F.Mask" "F.Paste")
			(net "P3V3_AUX")
		)
		(zone
			(layer "F.Cu")
			(hatch none 0.5)
			(connect_pads
				(clearance 0)
			)
			(min_thickness 0.25)
			(keepout
				(tracks not_allowed)
				(vias allowed)
				(pads allowed)
				(copperpour not_allowed)
				(footprints allowed)
			)
			(placement
				(enabled no)
				(sheetname "")
			)
			(fill
				(thermal_gap 0.5)
				(thermal_bridge_width 0.5)
				(island_removal_mode 0)
			)
			(polygon
				(pts
					(xy 444.714376 -122.841258) (xy 444.714376 -122.714258) (xy 444.714376 -119.742458) (xy 444.714376 -119.74195)
					(xy 442.428376 -119.74195) (xy 442.428376 -119.742458) (xy 442.428376 -119.869458) (xy 442.428376 -121.291858)
					(xy 442.529976 -121.291858) (xy 442.529976 -119.869458) (xy 444.612776 -119.869458) (xy 444.612776 -122.714258)
					(xy 442.529976 -122.714258) (xy 442.529976 -121.317258) (xy 442.428376 -121.317258) (xy 442.428376 -122.714258)
					(xy 442.428376 -122.841258) (xy 442.428376 -122.841766) (xy 444.714376 -122.841766)
				)
			)
		)
	)
	(footprint ""
		(layer "F.Cu")
		(at 200.809098 -26.03373)
		(property "Reference" "R4066"
			(at 0 0 0)
			(layer "F.SilkS")
			(hide yes)
			(effects
				(font
					(size 1.27 1.27)
				)
			)
		)
		(property "Value" ""
			(at 0 0 0)
			(layer "F.Fab")
			(effects
				(font
					(size 1.27 1.27)
				)
			)
		)
		(duplicate_pad_numbers_are_jumpers no)
		(fp_line
			(start -0.7874 -0.4064)
			(end 0.7874 -0.4064)
			(stroke
				(width 0.1524)
				(type default)
			)
			(layer "F.SilkS")
		)
		(fp_line
			(start -0.7874 0.4064)
			(end -0.7874 -0.4064)
			(stroke
				(width 0.1524)
				(type default)
			)
			(layer "F.SilkS")
		)
		(fp_line
			(start 0.7874 -0.4064)
			(end 0.7874 0.4064)
			(stroke
				(width 0.1524)
				(type default)
			)
			(layer "F.SilkS")
		)
		(fp_line
			(start 0.7874 0.4064)
			(end -0.7874 0.4064)
			(stroke
				(width 0.1524)
				(type default)
			)
			(layer "F.SilkS")
		)
		(fp_line
			(start -0.67945 -0.305054)
			(end -0.12065 -0.305054)
			(stroke
				(width 0.1)
				(type default)
			)
			(layer "F.Fab")
		)
		(fp_line
			(start -0.67945 0.3048)
			(end -0.67945 -0.305054)
			(stroke
				(width 0.1)
				(type default)
			)
			(layer "F.Fab")
		)
		(fp_line
			(start -0.12065 -0.305054)
			(end -0.12065 -0.2794)
			(stroke
				(width 0.1)
				(type default)
			)
			(layer "F.Fab")
		)
		(fp_line
			(start -0.12065 -0.2794)
			(end 0.12065 -0.2794)
			(stroke
				(width 0.1)
				(type default)
			)
			(layer "F.Fab")
		)
		(fp_line
			(start -0.12065 0.2794)
			(end -0.12065 0.3048)
			(stroke
				(width 0.1)
				(type default)
			)
			(layer "F.Fab")
		)
		(fp_line
			(start -0.12065 0.3048)
			(end -0.67945 0.3048)
			(stroke
				(width 0.1)
				(type default)
			)
			(layer "F.Fab")
		)
		(fp_line
			(start 0.120396 0.2794)
			(end -0.12065 0.2794)
			(stroke
				(width 0.1)
				(type default)
			)
			(layer "F.Fab")
		)
		(fp_line
			(start 0.120396 0.3048)
			(end 0.120396 0.2794)
			(stroke
				(width 0.1)
				(type default)
			)
			(layer "F.Fab")
		)
		(fp_line
			(start 0.12065 -0.3048)
			(end 0.67945 -0.3048)
			(stroke
				(width 0.1)
				(type default)
			)
			(layer "F.Fab")
		)
		(fp_line
			(start 0.12065 -0.2794)
			(end 0.12065 -0.3048)
			(stroke
				(width 0.1)
				(type default)
			)
			(layer "F.Fab")
		)
		(fp_line
			(start 0.67945 -0.3048)
			(end 0.67945 0.3048)
			(stroke
				(width 0.1)
				(type default)
			)
			(layer "F.Fab")
		)
		(fp_line
			(start 0.67945 0.3048)
			(end 0.120396 0.3048)
			(stroke
				(width 0.1)
				(type default)
			)
			(layer "F.Fab")
		)
		(pad "1" smd circle
			(at -0.40005 0)
			(size 0 0)
			(layers "F.Cu" "F.Mask" "F.Paste")
			(net "P3V3_AUX")
		)
		(pad "2" smd circle
			(at 0.40005 0)
			(size 0 0)
			(layers "F.Cu" "F.Mask" "F.Paste")
			(net "PRSNT_SSD7_R_N")
		)
	)
	(footprint ""
		(layer "F.Cu")
		(at 416.402012 -350.098614 90)
		(property "Reference" "C2446"
			(at 0 0 90)
			(layer "F.SilkS")
			(hide yes)
			(effects
				(font
					(size 1.27 1.27)
				)
			)
		)
		(property "Value" ""
			(at 0 0 90)
			(layer "F.Fab")
			(effects
				(font
					(size 1.27 1.27)
				)
			)
		)
		(duplicate_pad_numbers_are_jumpers no)
		(fp_line
			(start 0.299974 -0.150114)
			(end 0.299974 0.150114)
			(stroke
				(width 0.1)
				(type default)
			)
			(layer "F.Fab")
		)
		(fp_line
			(start -0.299974 -0.150114)
			(end 0.299974 -0.150114)
			(stroke
				(width 0.1)
				(type default)
			)
			(layer "F.Fab")
		)
		(fp_line
			(start 0.299974 0.150114)
			(end -0.299974 0.150114)
			(stroke
				(width 0.1)
				(type default)
			)
			(layer "F.Fab")
		)
		(fp_line
			(start -0.299974 0.150114)
			(end -0.299974 -0.150114)
			(stroke
				(width 0.1)
				(type default)
			)
			(layer "F.Fab")
		)
		(pad "1" smd rect
			(at -0.2667 0 90)
			(size 0.3048 0.381)
			(layers "F.Cu" "F.Mask" "F.Paste")
			(net "P5E_PEX3_STN4_TX_DN<76>")
		)
		(pad "2" smd rect
			(at 0.2667 0 90)
			(size 0.3048 0.381)
			(layers "F.Cu" "F.Mask" "F.Paste")
			(net "P5E_PEX3_STN4_TX_C_DN<76>")
		)
	)
	(footprint ""
		(layer "F.Cu")
		(at 173.394116 -35.264852)
		(property "Reference" "R5679"
			(at 0 0 0)
			(layer "F.SilkS")
			(hide yes)
			(effects
				(font
					(size 1.27 1.27)
				)
			)
		)
		(property "Value" ""
			(at 0 0 0)
			(layer "F.Fab")
			(effects
				(font
					(size 1.27 1.27)
				)
			)
		)
		(duplicate_pad_numbers_are_jumpers no)
		(fp_line
			(start -0.7874 -0.4064)
			(end 0.7874 -0.4064)
			(stroke
				(width 0.1524)
				(type default)
			)
			(layer "F.SilkS")
		)
		(fp_line
			(start -0.7874 0.4064)
			(end -0.7874 -0.4064)
			(stroke
				(width 0.1524)
				(type default)
			)
			(layer "F.SilkS")
		)
		(fp_line
			(start 0.7874 -0.4064)
			(end 0.7874 0.4064)
			(stroke
				(width 0.1524)
				(type default)
			)
			(layer "F.SilkS")
		)
		(fp_line
			(start 0.7874 0.4064)
			(end -0.7874 0.4064)
			(stroke
				(width 0.1524)
				(type default)
			)
			(layer "F.SilkS")
		)
		(fp_line
			(start -0.67945 -0.305054)
			(end -0.12065 -0.305054)
			(stroke
				(width 0.1)
				(type default)
			)
			(layer "F.Fab")
		)
		(fp_line
			(start -0.67945 0.3048)
			(end -0.67945 -0.305054)
			(stroke
				(width 0.1)
				(type default)
			)
			(layer "F.Fab")
		)
		(fp_line
			(start -0.12065 -0.305054)
			(end -0.12065 -0.2794)
			(stroke
				(width 0.1)
				(type default)
			)
			(layer "F.Fab")
		)
		(fp_line
			(start -0.12065 -0.2794)
			(end 0.12065 -0.2794)
			(stroke
				(width 0.1)
				(type default)
			)
			(layer "F.Fab")
		)
		(fp_line
			(start -0.12065 0.2794)
			(end -0.12065 0.3048)
			(stroke
				(width 0.1)
				(type default)
			)
			(layer "F.Fab")
		)
		(fp_line
			(start -0.12065 0.3048)
			(end -0.67945 0.3048)
			(stroke
				(width 0.1)
				(type default)
			)
			(layer "F.Fab")
		)
		(fp_line
			(start 0.120396 0.2794)
			(end -0.12065 0.2794)
			(stroke
				(width 0.1)
				(type default)
			)
			(layer "F.Fab")
		)
		(fp_line
			(start 0.120396 0.3048)
			(end 0.120396 0.2794)
			(stroke
				(width 0.1)
				(type default)
			)
			(layer "F.Fab")
		)
		(fp_line
			(start 0.12065 -0.3048)
			(end 0.67945 -0.3048)
			(stroke
				(width 0.1)
				(type default)
			)
			(layer "F.Fab")
		)
		(fp_line
			(start 0.12065 -0.2794)
			(end 0.12065 -0.3048)
			(stroke
				(width 0.1)
				(type default)
			)
			(layer "F.Fab")
		)
		(fp_line
			(start 0.67945 -0.3048)
			(end 0.67945 0.3048)
			(stroke
				(width 0.1)
				(type default)
			)
			(layer "F.Fab")
		)
		(fp_line
			(start 0.67945 0.3048)
			(end 0.120396 0.3048)
			(stroke
				(width 0.1)
				(type default)
			)
			(layer "F.Fab")
		)
		(pad "1" smd circle
			(at -0.40005 0)
			(size 0 0)
			(layers "F.Cu" "F.Mask" "F.Paste")
			(net "RST_SMB_SSD6_ISO_N")
		)
		(pad "2" smd circle
			(at 0.40005 0)
			(size 0 0)
			(layers "F.Cu" "F.Mask" "F.Paste")
			(net "GND")
		)
	)
)
